# T6G (Grand Teton) — schematic netlist excerpt (pin names and nets, part order shuffled) for the footprints in the layout excerpt that follows; sources: Cadence DE-HDL packaged netlist, KiCad conversion of 04192023_DAF0TMB3IC0_F0TG_MB_C_brd_V02_OCP.brd

R1250  Q_RES  0 5% EMPTY  pkg 0402LF  page 258 : A = P1V8_CPU1_RT_1D_ADC ; B = P1V8_CPU1_RT_1D_ADC_MAM
R332  Q_RES  2.2K 5% EMPTY  pkg 0402LF  page 151 : A = I3C_BMC_SWB_SCL ; B = P3V3_AUX

(kicad_pcb
	(version 20260206)
	(generator "pcbnew")
	(generator_version "10.0")
	(general
		(thickness 1.6)
		(legacy_teardrops no)
	)
	(paper "A4")
	(title_block
		(title "04192023_DAF0TMB3IC0_F0TG_MB_C_brd_V02_OCP.brd")
		(comment 1 "Grand Teton / footprints 7096-7097 of 8354")
	)
	(layers
		(0 "F.Cu" signal "TOP")
		(4 "In1.Cu" signal "GND")
		(6 "In2.Cu" signal "IN1")
		(8 "In3.Cu" signal "GND1")
		(10 "In4.Cu" signal "IN2")
		(12 "In5.Cu" signal "GND2")
		(14 "In6.Cu" signal "IN3")
		(16 "In7.Cu" signal "GND3")
		(18 "In8.Cu" signal "VCC")
		(20 "In9.Cu" signal "VCC1")
		(22 "In10.Cu" signal "GND4")
		(24 "In11.Cu" signal "IN4")
		(26 "In12.Cu" signal "GND5")
		(28 "In13.Cu" signal "IN5")
		(30 "In14.Cu" signal "GND6")
		(32 "In15.Cu" signal "IN6")
		(34 "In16.Cu" signal "GND7")
		(2 "B.Cu" signal "BOTTOM")
		(9 "F.Adhes" user "F.Adhesive")
		(11 "B.Adhes" user "B.Adhesive")
		(13 "F.Paste" user "Package Geometry/Pastemask Top")
		(15 "B.Paste" user "Package Geometry/Pastemask Bottom")
		(5 "F.SilkS" user "Ref Des/Silkscreen Top")
		(7 "B.SilkS" user "Ref Des/Silkscreen Bottom")
		(1 "F.Mask" user "Board Geometry/Soldermask Top")
		(3 "B.Mask" user "Board Geometry/Soldermask Bottom")
		(17 "Dwgs.User" user "User.Drawings")
		(19 "Cmts.User" user "User.Comments")
		(21 "Eco1.User" user "User.Eco1")
		(23 "Eco2.User" user "User.Eco2")
		(25 "Edge.Cuts" user "Board Geometry/Outline")
		(27 "Margin" user)
		(31 "F.CrtYd" user "Package Geometry/Place Bound Top")
		(29 "B.CrtYd" user "Package Geometry/Place Bound Bottom")
		(35 "F.Fab" user "Ref Des/Assembly Top")
		(33 "B.Fab" user "Ref Des/Assembly Bottom")
	)
	(footprint ""
		(layer "B.Cu")
		(at 174.317914 -13.762228 -90)
		(property "Reference" "R332"
			(at 0 0 90)
			(layer "B.SilkS")
			(hide yes)
			(effects
				(font
					(size 1.27 1.27)
				)
				(justify mirror)
			)
		)
		(property "Value" ""
			(at 0 0 90)
			(layer "B.Fab")
			(effects
				(font
					(size 1.27 1.27)
				)
				(justify mirror)
			)
		)
		(duplicate_pad_numbers_are_jumpers no)
		(fp_line
			(start -0.7874 0.4064)
			(end 0.7874 0.4064)
			(stroke
				(width 0.1524)
				(type default)
			)
			(layer "B.SilkS")
		)
		(fp_line
			(start 0.7874 0.4064)
			(end 0.7874 -0.4064)
			(stroke
				(width 0.1524)
				(type default)
			)
			(layer "B.SilkS")
		)
		(fp_line
			(start -0.7874 -0.4064)
			(end -0.7874 0.4064)
			(stroke
				(width 0.1524)
				(type default)
			)
			(layer "B.SilkS")
		)
		(fp_line
			(start 0.7874 -0.4064)
			(end -0.7874 -0.4064)
			(stroke
				(width 0.1524)
				(type default)
			)
			(layer "B.SilkS")
		)
		(fp_line
			(start -0.67945 0.3048)
			(end -0.120396 0.3048)
			(stroke
				(width 0.1)
				(type default)
			)
			(layer "B.Fab")
		)
		(fp_line
			(start -0.120396 0.3048)
			(end -0.120396 0.2794)
			(stroke
				(width 0.1)
				(type default)
			)
			(layer "B.Fab")
		)
		(fp_line
			(start 0.12065 0.3048)
			(end 0.67945 0.3048)
			(stroke
				(width 0.1)
				(type default)
			)
			(layer "B.Fab")
		)
		(fp_line
			(start 0.67945 0.3048)
			(end 0.67945 -0.305054)
			(stroke
				(width 0.1)
				(type default)
			)
			(layer "B.Fab")
		)
		(fp_line
			(start -0.120396 0.2794)
			(end 0.12065 0.2794)
			(stroke
				(width 0.1)
				(type default)
			)
			(layer "B.Fab")
		)
		(fp_line
			(start 0.12065 0.2794)
			(end 0.12065 0.3048)
			(stroke
				(width 0.1)
				(type default)
			)
			(layer "B.Fab")
		)
		(fp_line
			(start -0.12065 -0.2794)
			(end -0.12065 -0.3048)
			(stroke
				(width 0.1)
				(type default)
			)
			(layer "B.Fab")
		)
		(fp_line
			(start 0.12065 -0.2794)
			(end -0.12065 -0.2794)
			(stroke
				(width 0.1)
				(type default)
			)
			(layer "B.Fab")
		)
		(fp_line
			(start -0.67945 -0.3048)
			(end -0.67945 0.3048)
			(stroke
				(width 0.1)
				(type default)
			)
			(layer "B.Fab")
		)
		(fp_line
			(start -0.12065 -0.3048)
			(end -0.67945 -0.3048)
			(stroke
				(width 0.1)
				(type default)
			)
			(layer "B.Fab")
		)
		(fp_line
			(start 0.12065 -0.305054)
			(end 0.12065 -0.2794)
			(stroke
				(width 0.1)
				(type default)
			)
			(layer "B.Fab")
		)
		(fp_line
			(start 0.67945 -0.305054)
			(end 0.12065 -0.305054)
			(stroke
				(width 0.1)
				(type default)
			)
			(layer "B.Fab")
		)
		(pad "1" smd circle
			(at 0.40005 0 90)
			(size 0 0)
			(layers "B.Cu" "B.Mask" "B.Paste")
			(net "I3C_BMC_SWB_SCL")
		)
		(pad "2" smd circle
			(at -0.40005 0 90)
			(size 0 0)
			(layers "B.Cu" "B.Mask" "B.Paste")
			(net "P3V3_AUX")
		)
	)
	(footprint ""
		(layer "B.Cu")
		(at 231.872536 -326.07885 180)
		(property "Reference" "R1250"
			(at 0 0 0)
			(layer "B.SilkS")
			(hide yes)
			(effects
				(font
					(size 1.27 1.27)
				)
				(justify mirror)
			)
		)
		(property "Value" ""
			(at 0 0 0)
			(layer "B.Fab")
			(effects
				(font
					(size 1.27 1.27)
				)
				(justify mirror)
			)
		)
		(duplicate_pad_numbers_are_jumpers no)
		(fp_line
			(start 0.7874 0.4064)
			(end 0.7874 -0.4064)
			(stroke
				(width 0.1524)
				(type default)
			)
			(layer "B.SilkS")
		)
		(fp_line
			(start 0.7874 -0.4064)
			(end -0.7874 -0.4064)
			(stroke
				(width 0.1524)
				(type default)
			)
			(layer "B.SilkS")
		)
		(fp_line
			(start -0.7874 0.4064)
			(end 0.7874 0.4064)
			(stroke
				(width 0.1524)
				(type default)
			)
			(layer "B.SilkS")
		)
		(fp_line
			(start -0.7874 -0.4064)
			(end -0.7874 0.4064)
			(stroke
				(width 0.1524)
				(type default)
			)
			(layer "B.SilkS")
		)
		(fp_line
			(start 0.67945 0.3048)
			(end 0.67945 -0.305054)
			(stroke
				(width 0.1)
				(type default)
			)
			(layer "B.Fab")
		)
		(fp_line
			(start 0.67945 -0.305054)
			(end 0.12065 -0.305054)
			(stroke
				(width 0.1)
				(type default)
			)
			(layer "B.Fab")
		)
		(fp_line
			(start 0.12065 0.3048)
			(end 0.67945 0.3048)
			(stroke
				(width 0.1)
				(type default)
			)
			(layer "B.Fab")
		)
		(fp_line
			(start 0.12065 0.2794)
			(end 0.12065 0.3048)
			(stroke
				(width 0.1)
				(type default)
			)
			(layer "B.Fab")
		)
		(fp_line
			(start 0.12065 -0.2794)
			(end -0.12065 -0.2794)
			(stroke
				(width 0.1)
				(type default)
			)
			(layer "B.Fab")
		)
		(fp_line
			(start 0.12065 -0.305054)
			(end 0.12065 -0.2794)
			(stroke
				(width 0.1)
				(type default)
			)
			(layer "B.Fab")
		)
		(fp_line
			(start -0.120396 0.3048)
			(end -0.120396 0.2794)
			(stroke
				(width 0.1)
				(type default)
			)
			(layer "B.Fab")
		)
		(fp_line
			(start -0.120396 0.2794)
			(end 0.12065 0.2794)
			(stroke
				(width 0.1)
				(type default)
			)
			(layer "B.Fab")
		)
		(fp_line
			(start -0.12065 -0.2794)
			(end -0.12065 -0.3048)
			(stroke
				(width 0.1)
				(type default)
			)
			(layer "B.Fab")
		)
		(fp_line
			(start -0.12065 -0.3048)
			(end -0.67945 -0.3048)
			(stroke
				(width 0.1)
				(type default)
			)
			(layer "B.Fab")
		)
		(fp_line
			(start -0.67945 0.3048)
			(end -0.120396 0.3048)
			(stroke
				(width 0.1)
				(type default)
			)
			(layer "B.Fab")
		)
		(fp_line
			(start -0.67945 -0.3048)
			(end -0.67945 0.3048)
			(stroke
				(width 0.1)
				(type default)
			)
			(layer "B.Fab")
		)
		(pad "1" smd rect
			(at 0.40005 0 180)
			(size 0.4572 0.508)
			(layers "B.Cu" "B.Mask" "B.Paste")
			(net "P1V8_CPU1_RT_1D_ADC")
		)
		(pad "2" smd rect
			(at -0.40005 0 180)
			(size 0.4572 0.508)
			(layers "B.Cu" "B.Mask" "B.Paste")
			(net "P1V8_CPU1_RT_1D_ADC_MAM")
		)
	)
)
